(kicad_pcb
	(version 20260206)
	(generator "pcbnew")
	(generator_version "10.0")
	(general
		(thickness 1.6)
		(legacy_teardrops no)
	)
	(paper "A4")
	(title_block
		(title "03242023_DA0F0TMBIJ0_F0T_Motherboard_J_brd_V01_OCP.brd")
		(comment 1 "Grand Teton / footprints 3547-3552 of 6105")
	)
	(layers
		(0 "F.Cu" signal "TOP")
		(4 "In1.Cu" signal "GND")
		(6 "In2.Cu" signal "IN1")
		(8 "In3.Cu" signal "GND1")
		(10 "In4.Cu" signal "IN2")
		(12 "In5.Cu" signal "GND2")
		(14 "In6.Cu" signal "IN3")
		(16 "In7.Cu" signal "GND3")
		(18 "In8.Cu" signal "VCC")
		(20 "In9.Cu" signal "VCC1")
		(22 "In10.Cu" signal "GND4")
		(24 "In11.Cu" signal "IN4")
		(26 "In12.Cu" signal "GND5")
		(28 "In13.Cu" signal "IN5")
		(30 "In14.Cu" signal "GND6")
		(32 "In15.Cu" signal "IN6")
		(34 "In16.Cu" signal "GND7")
		(2 "B.Cu" signal "BOTTOM")
		(9 "F.Adhes" user "F.Adhesive")
		(11 "B.Adhes" user "B.Adhesive")
		(13 "F.Paste" user "Package Geometry/Pastemask Top")
		(15 "B.Paste" user "Package Geometry/Pastemask Bottom")
		(5 "F.SilkS" user "Ref Des/Silkscreen Top")
		(7 "B.SilkS" user "Ref Des/Silkscreen Bottom")
		(1 "F.Mask" user "Board Geometry/Soldermask Top")
		(3 "B.Mask" user "Board Geometry/Soldermask Bottom")
		(17 "Dwgs.User" user "User.Drawings")
		(19 "Cmts.User" user "User.Comments")
		(21 "Eco1.User" user "User.Eco1")
		(23 "Eco2.User" user "User.Eco2")
		(25 "Edge.Cuts" user "Board Geometry/Outline")
		(27 "Margin" user)
		(31 "F.CrtYd" user "Package Geometry/Place Bound Top")
		(29 "B.CrtYd" user "Package Geometry/Place Bound Bottom")
		(35 "F.Fab" user "Ref Des/Assembly Top")
		(33 "B.Fab" user "Ref Des/Assembly Bottom")
	)
	(footprint ""
		(layer "F.Cu")
		(at 166.37 -23.713948 90)
		(property "Reference" "R144"
			(at 0 0 90)
			(layer "F.SilkS")
			(hide yes)
			(effects
				(font
					(size 1.27 1.27)
				)
			)
		)
		(property "Value" ""
			(at 0 0 90)
			(layer "F.Fab")
			(effects
				(font
					(size 1.27 1.27)
				)
			)
		)
		(duplicate_pad_numbers_are_jumpers no)
		(fp_line
			(start 0.7874 -0.4064)
			(end 0.7874 0.4064)
			(stroke
				(width 0.1524)
				(type default)
			)
			(layer "F.SilkS")
		)
		(fp_line
			(start -0.7874 -0.4064)
			(end 0.7874 -0.4064)
			(stroke
				(width 0.1524)
				(type default)
			)
			(layer "F.SilkS")
		)
		(fp_line
			(start 0.7874 0.4064)
			(end -0.7874 0.4064)
			(stroke
				(width 0.1524)
				(type default)
			)
			(layer "F.SilkS")
		)
		(fp_line
			(start -0.7874 0.4064)
			(end -0.7874 -0.4064)
			(stroke
				(width 0.1524)
				(type default)
			)
			(layer "F.SilkS")
		)
		(fp_line
			(start -0.12065 -0.305054)
			(end -0.12065 -0.2794)
			(stroke
				(width 0.1)
				(type default)
			)
			(layer "F.Fab")
		)
		(fp_line
			(start -0.67945 -0.305054)
			(end -0.12065 -0.305054)
			(stroke
				(width 0.1)
				(type default)
			)
			(layer "F.Fab")
		)
		(fp_line
			(start 0.67945 -0.3048)
			(end 0.67945 0.3048)
			(stroke
				(width 0.1)
				(type default)
			)
			(layer "F.Fab")
		)
		(fp_line
			(start 0.12065 -0.3048)
			(end 0.67945 -0.3048)
			(stroke
				(width 0.1)
				(type default)
			)
			(layer "F.Fab")
		)
		(fp_line
			(start 0.12065 -0.2794)
			(end 0.12065 -0.3048)
			(stroke
				(width 0.1)
				(type default)
			)
			(layer "F.Fab")
		)
		(fp_line
			(start -0.12065 -0.2794)
			(end 0.12065 -0.2794)
			(stroke
				(width 0.1)
				(type default)
			)
			(layer "F.Fab")
		)
		(fp_line
			(start 0.120396 0.2794)
			(end -0.12065 0.2794)
			(stroke
				(width 0.1)
				(type default)
			)
			(layer "F.Fab")
		)
		(fp_line
			(start -0.12065 0.2794)
			(end -0.12065 0.3048)
			(stroke
				(width 0.1)
				(type default)
			)
			(layer "F.Fab")
		)
		(fp_line
			(start 0.67945 0.3048)
			(end 0.120396 0.3048)
			(stroke
				(width 0.1)
				(type default)
			)
			(layer "F.Fab")
		)
		(fp_line
			(start 0.120396 0.3048)
			(end 0.120396 0.2794)
			(stroke
				(width 0.1)
				(type default)
			)
			(layer "F.Fab")
		)
		(fp_line
			(start -0.12065 0.3048)
			(end -0.67945 0.3048)
			(stroke
				(width 0.1)
				(type default)
			)
			(layer "F.Fab")
		)
		(fp_line
			(start -0.67945 0.3048)
			(end -0.67945 -0.305054)
			(stroke
				(width 0.1)
				(type default)
			)
			(layer "F.Fab")
		)
		(pad "1" smd circle
			(at -0.40005 0 90)
			(size 0 0)
			(layers "F.Cu" "F.Mask" "F.Paste")
			(net "PECI_BMC")
		)
		(pad "2" smd circle
			(at 0.40005 0 90)
			(size 0 0)
			(layers "F.Cu" "F.Mask" "F.Paste")
			(net "PECI_BMC_R")
		)
	)
	(footprint ""
		(layer "F.Cu")
		(at 163.88715 -425.245276 -90)
		(property "Reference" "U175"
			(at 1.581404 -2.540762 90)
			(unlocked yes)
			(layer "F.SilkS")
			(effects
				(font
					(size 0.7874 0.5842)
					(thickness 0.1524)
				)
				(justify left)
			)
		)
		(property "Value" ""
			(at 0 0 270)
			(layer "F.Fab")
			(effects
				(font
					(size 1.27 1.27)
				)
			)
		)
		(duplicate_pad_numbers_are_jumpers no)
		(fp_line
			(start -1.3716 1.524)
			(end -1.3716 -1.524)
			(stroke
				(width 0.1524)
				(type default)
			)
			(layer "F.SilkS")
		)
		(fp_line
			(start 1.3716 1.524)
			(end -1.3716 1.524)
			(stroke
				(width 0.1524)
				(type default)
			)
			(layer "F.SilkS")
		)
		(fp_line
			(start 0 -1.016)
			(end 0.508 -1.524)
			(stroke
				(width 0.1524)
				(type default)
			)
			(layer "F.SilkS")
		)
		(fp_line
			(start -1.3716 -1.524)
			(end -0.508 -1.524)
			(stroke
				(width 0.1524)
				(type default)
			)
			(layer "F.SilkS")
		)
		(fp_line
			(start -0.508 -1.524)
			(end 0 -1.016)
			(stroke
				(width 0.1524)
				(type default)
			)
			(layer "F.SilkS")
		)
		(fp_line
			(start 0.508 -1.524)
			(end 1.3716 -1.524)
			(stroke
				(width 0.1524)
				(type default)
			)
			(layer "F.SilkS")
		)
		(fp_line
			(start 1.3716 -1.524)
			(end 1.3716 1.524)
			(stroke
				(width 0.1524)
				(type default)
			)
			(layer "F.SilkS")
		)
		(fp_poly
			(pts
				(xy -3.60172 -1.344168) (xy -3.048 -1.016) (xy -3.60172 -0.719328)
			)
			(stroke
				(width 0)
				(type default)
			)
			(fill yes)
			(layer "F.SilkS")
		)
		(fp_line
			(start -1.5494 1.524)
			(end -1.5494 1.0668)
			(stroke
				(width 0.1)
				(type default)
			)
			(layer "F.Fab")
		)
		(fp_line
			(start 1.5494 1.524)
			(end -1.5494 1.524)
			(stroke
				(width 0.1)
				(type default)
			)
			(layer "F.Fab")
		)
		(fp_line
			(start -2.54 1.0668)
			(end -2.54 -1.0668)
			(stroke
				(width 0.1)
				(type default)
			)
			(layer "F.Fab")
		)
		(fp_line
			(start -1.5494 1.0668)
			(end -2.54 1.0668)
			(stroke
				(width 0.1)
				(type default)
			)
			(layer "F.Fab")
		)
		(fp_line
			(start -1.5494 1.0668)
			(end -1.5494 -1.0668)
			(stroke
				(width 0.1)
				(type default)
			)
			(layer "F.Fab")
		)
		(fp_line
			(start 1.5494 1.0668)
			(end 1.5494 1.524)
			(stroke
				(width 0.1)
				(type default)
			)
			(layer "F.Fab")
		)
		(fp_line
			(start 2.54 1.0668)
			(end 1.5494 1.0668)
			(stroke
				(width 0.1)
				(type default)
			)
			(layer "F.Fab")
		)
		(fp_line
			(start -2.54 -1.0668)
			(end -1.5494 -1.0668)
			(stroke
				(width 0.1)
				(type default)
			)
			(layer "F.Fab")
		)
		(fp_line
			(start -1.5494 -1.0668)
			(end -1.5494 -1.524)
			(stroke
				(width 0.1)
				(type default)
			)
			(layer "F.Fab")
		)
		(fp_line
			(start 1.5494 -1.0668)
			(end 1.5494 1.0668)
			(stroke
				(width 0.1)
				(type default)
			)
			(layer "F.Fab")
		)
		(fp_line
			(start 1.5494 -1.0668)
			(end 2.54 -1.0668)
			(stroke
				(width 0.1)
				(type default)
			)
			(layer "F.Fab")
		)
		(fp_line
			(start 2.54 -1.0668)
			(end 2.54 1.0668)
			(stroke
				(width 0.1)
				(type default)
			)
			(layer "F.Fab")
		)
		(fp_line
			(start -1.5494 -1.524)
			(end 1.5494 -1.524)
			(stroke
				(width 0.1)
				(type default)
			)
			(layer "F.Fab")
		)
		(fp_line
			(start 1.5494 -1.524)
			(end 1.5494 -1.0668)
			(stroke
				(width 0.1)
				(type default)
			)
			(layer "F.Fab")
		)
		(fp_poly
			(pts
				(xy -3.60172 -0.719328) (xy -3.60172 -1.344168) (xy -3.048 -1.016)
			)
			(stroke
				(width 0)
				(type default)
			)
			(fill yes)
			(layer "F.Fab")
		)
		(pad "1" smd rect
			(at -2.232406 -0.975106 180)
			(size 0.3556 1.4224)
			(layers "F.Cu" "F.Mask" "F.Paste")
			(net "SMB_BMC_SWB_EN_R")
		)
		(pad "2" smd rect
			(at -2.232406 -0.32512 180)
			(size 0.3556 1.4224)
			(layers "F.Cu" "F.Mask" "F.Paste")
			(net "SMB_BMC_SWB_BUF_R_SCL")
		)
		(pad "3" smd rect
			(at -2.232406 0.32512 180)
			(size 0.3556 1.4224)
			(layers "F.Cu" "F.Mask" "F.Paste")
			(net "SMB_BMC_SWB_R_SCL")
		)
		(pad "4" smd rect
			(at -2.232406 0.975106 180)
			(size 0.3556 1.4224)
			(layers "F.Cu" "F.Mask" "F.Paste")
			(net "GND")
		)
		(pad "5" smd rect
			(at 2.232406 0.975106 180)
			(size 0.3556 1.4224)
			(layers "F.Cu" "F.Mask" "F.Paste")
			(net "Net_1934")
		)
		(pad "6" smd rect
			(at 2.232406 0.32512 180)
			(size 0.3556 1.4224)
			(layers "F.Cu" "F.Mask" "F.Paste")
			(net "SMB_BMC_SWB_R_SDA")
		)
		(pad "7" smd rect
			(at 2.232406 -0.32512 180)
			(size 0.3556 1.4224)
			(layers "F.Cu" "F.Mask" "F.Paste")
			(net "SMB_BMC_SWB_BUF_R_SDA")
		)
		(pad "8" smd rect
			(at 2.232406 -0.975106 180)
			(size 0.3556 1.4224)
			(layers "F.Cu" "F.Mask" "F.Paste")
			(net "P3V3_AUX")
		)
	)
	(footprint ""
		(layer "F.Cu")
		(at 27.0383 -126.332996 180)
		(property "Reference" "PC476"
			(at 0 0 180)
			(layer "F.SilkS")
			(hide yes)
			(effects
				(font
					(size 1.27 1.27)
				)
			)
		)
		(property "Value" ""
			(at 0 0 180)
			(layer "F.Fab")
			(effects
				(font
					(size 1.27 1.27)
				)
			)
		)
		(duplicate_pad_numbers_are_jumpers no)
		(fp_line
			(start 0.7874 0.4064)
			(end -0.7874 0.4064)
			(stroke
				(width 0.1524)
				(type default)
			)
			(layer "F.SilkS")
		)
		(fp_line
			(start 0.7874 -0.4064)
			(end 0.7874 0.4064)
			(stroke
				(width 0.1524)
				(type default)
			)
			(layer "F.SilkS")
		)
		(fp_line
			(start -0.7874 0.4064)
			(end -0.7874 -0.4064)
			(stroke
				(width 0.1524)
				(type default)
			)
			(layer "F.SilkS")
		)
		(fp_line
			(start -0.7874 -0.4064)
			(end 0.7874 -0.4064)
			(stroke
				(width 0.1524)
				(type default)
			)
			(layer "F.SilkS")
		)
		(fp_line
			(start 0.67945 0.3048)
			(end 0.120396 0.3048)
			(stroke
				(width 0.1)
				(type default)
			)
			(layer "F.Fab")
		)
		(fp_line
			(start 0.67945 -0.3048)
			(end 0.67945 0.3048)
			(stroke
				(width 0.1)
				(type default)
			)
			(layer "F.Fab")
		)
		(fp_line
			(start 0.12065 -0.2794)
			(end 0.12065 -0.3048)
			(stroke
				(width 0.1)
				(type default)
			)
			(layer "F.Fab")
		)
		(fp_line
			(start 0.12065 -0.3048)
			(end 0.67945 -0.3048)
			(stroke
				(width 0.1)
				(type default)
			)
			(layer "F.Fab")
		)
		(fp_line
			(start 0.120396 0.3048)
			(end 0.120396 0.2794)
			(stroke
				(width 0.1)
				(type default)
			)
			(layer "F.Fab")
		)
		(fp_line
			(start 0.120396 0.2794)
			(end -0.12065 0.2794)
			(stroke
				(width 0.1)
				(type default)
			)
			(layer "F.Fab")
		)
		(fp_line
			(start -0.12065 0.3048)
			(end -0.67945 0.3048)
			(stroke
				(width 0.1)
				(type default)
			)
			(layer "F.Fab")
		)
		(fp_line
			(start -0.12065 0.2794)
			(end -0.12065 0.3048)
			(stroke
				(width 0.1)
				(type default)
			)
			(layer "F.Fab")
		)
		(fp_line
			(start -0.12065 -0.2794)
			(end 0.12065 -0.2794)
			(stroke
				(width 0.1)
				(type default)
			)
			(layer "F.Fab")
		)
		(fp_line
			(start -0.12065 -0.305054)
			(end -0.12065 -0.2794)
			(stroke
				(width 0.1)
				(type default)
			)
			(layer "F.Fab")
		)
		(fp_line
			(start -0.67945 0.3048)
			(end -0.67945 -0.305054)
			(stroke
				(width 0.1)
				(type default)
			)
			(layer "F.Fab")
		)
		(fp_line
			(start -0.67945 -0.305054)
			(end -0.12065 -0.305054)
			(stroke
				(width 0.1)
				(type default)
			)
			(layer "F.Fab")
		)
		(pad "1" smd circle
			(at -0.40005 0 180)
			(size 0 0)
			(layers "F.Cu" "F.Mask" "F.Paste")
			(net "PVCCINFAON_CPU1_VCC")
		)
		(pad "2" smd circle
			(at 0.40005 0 180)
			(size 0 0)
			(layers "F.Cu" "F.Mask" "F.Paste")
			(net "GND")
		)
	)
	(footprint ""
		(layer "F.Cu")
		(at 446.780158 -177.78476)
		(property "Reference" "PC1206"
			(at 0 0 0)
			(layer "F.SilkS")
			(hide yes)
			(effects
				(font
					(size 1.27 1.27)
				)
			)
		)
		(property "Value" ""
			(at 0 0 0)
			(layer "F.Fab")
			(effects
				(font
					(size 1.27 1.27)
				)
			)
		)
		(duplicate_pad_numbers_are_jumpers no)
		(fp_line
			(start -1.524 -0.762)
			(end 1.524 -0.762)
			(stroke
				(width 0.1524)
				(type default)
			)
			(layer "F.SilkS")
		)
		(fp_line
			(start -1.524 0.762)
			(end -1.524 -0.762)
			(stroke
				(width 0.1524)
				(type default)
			)
			(layer "F.SilkS")
		)
		(fp_line
			(start 1.524 -0.762)
			(end 1.524 0.762)
			(stroke
				(width 0.1524)
				(type default)
			)
			(layer "F.SilkS")
		)
		(fp_line
			(start 1.524 0.762)
			(end -1.524 0.762)
			(stroke
				(width 0.1524)
				(type default)
			)
			(layer "F.SilkS")
		)
		(fp_line
			(start -1.1049 -0.724916)
			(end -1.1049 0.724916)
			(stroke
				(width 0.1)
				(type default)
			)
			(layer "F.Fab")
		)
		(fp_line
			(start -1.1049 0.724916)
			(end 1.1049 0.724916)
			(stroke
				(width 0.1)
				(type default)
			)
			(layer "F.Fab")
		)
		(fp_line
			(start 1.1049 -0.724916)
			(end -1.1049 -0.724916)
			(stroke
				(width 0.1)
				(type default)
			)
			(layer "F.Fab")
		)
		(fp_line
			(start 1.1049 0.724916)
			(end 1.1049 -0.724916)
			(stroke
				(width 0.1)
				(type default)
			)
			(layer "F.Fab")
		)
		(pad "1" smd rect
			(at -0.889 0 180)
			(size 1.016 1.27)
			(layers "F.Cu" "F.Mask" "F.Paste")
			(net "PVNN_MAIN_CPU0")
		)
		(pad "2" smd rect
			(at 0.889 0 180)
			(size 1.016 1.27)
			(layers "F.Cu" "F.Mask" "F.Paste")
			(net "GND")
		)
	)
	(footprint ""
		(layer "F.Cu")
		(at 297.147234 -15.572994 180)
		(property "Reference" "R4196"
			(at 0 0 180)
			(layer "F.SilkS")
			(hide yes)
			(effects
				(font
					(size 1.27 1.27)
				)
			)
		)
		(property "Value" ""
			(at 0 0 180)
			(layer "F.Fab")
			(effects
				(font
					(size 1.27 1.27)
				)
			)
		)
		(duplicate_pad_numbers_are_jumpers no)
		(fp_line
			(start 0.7874 0.4064)
			(end -0.7874 0.4064)
			(stroke
				(width 0.1524)
				(type default)
			)
			(layer "F.SilkS")
		)
		(fp_line
			(start 0.7874 -0.4064)
			(end 0.7874 0.4064)
			(stroke
				(width 0.1524)
				(type default)
			)
			(layer "F.SilkS")
		)
		(fp_line
			(start -0.7874 0.4064)
			(end -0.7874 -0.4064)
			(stroke
				(width 0.1524)
				(type default)
			)
			(layer "F.SilkS")
		)
		(fp_line
			(start -0.7874 -0.4064)
			(end 0.7874 -0.4064)
			(stroke
				(width 0.1524)
				(type default)
			)
			(layer "F.SilkS")
		)
		(fp_line
			(start 0.67945 0.3048)
			(end 0.120396 0.3048)
			(stroke
				(width 0.1)
				(type default)
			)
			(layer "F.Fab")
		)
		(fp_line
			(start 0.67945 -0.3048)
			(end 0.67945 0.3048)
			(stroke
				(width 0.1)
				(type default)
			)
			(layer "F.Fab")
		)
		(fp_line
			(start 0.12065 -0.2794)
			(end 0.12065 -0.3048)
			(stroke
				(width 0.1)
				(type default)
			)
			(layer "F.Fab")
		)
		(fp_line
			(start 0.12065 -0.3048)
			(end 0.67945 -0.3048)
			(stroke
				(width 0.1)
				(type default)
			)
			(layer "F.Fab")
		)
		(fp_line
			(start 0.120396 0.3048)
			(end 0.120396 0.2794)
			(stroke
				(width 0.1)
				(type default)
			)
			(layer "F.Fab")
		)
		(fp_line
			(start 0.120396 0.2794)
			(end -0.12065 0.2794)
			(stroke
				(width 0.1)
				(type default)
			)
			(layer "F.Fab")
		)
		(fp_line
			(start -0.12065 0.3048)
			(end -0.67945 0.3048)
			(stroke
				(width 0.1)
				(type default)
			)
			(layer "F.Fab")
		)
		(fp_line
			(start -0.12065 0.2794)
			(end -0.12065 0.3048)
			(stroke
				(width 0.1)
				(type default)
			)
			(layer "F.Fab")
		)
		(fp_line
			(start -0.12065 -0.2794)
			(end 0.12065 -0.2794)
			(stroke
				(width 0.1)
				(type default)
			)
			(layer "F.Fab")
		)
		(fp_line
			(start -0.12065 -0.305054)
			(end -0.12065 -0.2794)
			(stroke
				(width 0.1)
				(type default)
			)
			(layer "F.Fab")
		)
		(fp_line
			(start -0.67945 0.3048)
			(end -0.67945 -0.305054)
			(stroke
				(width 0.1)
				(type default)
			)
			(layer "F.Fab")
		)
		(fp_line
			(start -0.67945 -0.305054)
			(end -0.12065 -0.305054)
			(stroke
				(width 0.1)
				(type default)
			)
			(layer "F.Fab")
		)
		(pad "1" smd circle
			(at -0.40005 0 180)
			(size 0 0)
			(layers "F.Cu" "F.Mask" "F.Paste")
			(net "P3V3_AUX")
		)
		(pad "2" smd circle
			(at 0.40005 0 180)
			(size 0 0)
			(layers "F.Cu" "F.Mask" "F.Paste")
			(net "U271_1_ADD1")
		)
	)
	(footprint ""
		(layer "F.Cu")
		(at 36.605718 -354.65385)
		(property "Reference" "PR702"
			(at 0 0 0)
			(layer "F.SilkS")
			(hide yes)
			(effects
				(font
					(size 1.27 1.27)
				)
			)
		)
		(property "Value" ""
			(at 0 0 0)
			(layer "F.Fab")
			(effects
				(font
					(size 1.27 1.27)
				)
			)
		)
		(duplicate_pad_numbers_are_jumpers no)
		(fp_line
			(start -0.7874 -0.4064)
			(end 0.7874 -0.4064)
			(stroke
				(width 0.1524)
				(type default)
			)
			(layer "F.SilkS")
		)
		(fp_line
			(start -0.7874 0.4064)
			(end -0.7874 -0.4064)
			(stroke
				(width 0.1524)
				(type default)
			)
			(layer "F.SilkS")
		)
		(fp_line
			(start 0.7874 -0.4064)
			(end 0.7874 0.4064)
			(stroke
				(width 0.1524)
				(type default)
			)
			(layer "F.SilkS")
		)
		(fp_line
			(start 0.7874 0.4064)
			(end -0.7874 0.4064)
			(stroke
				(width 0.1524)
				(type default)
			)
			(layer "F.SilkS")
		)
		(fp_line
			(start -0.67945 -0.305054)
			(end -0.12065 -0.305054)
			(stroke
				(width 0.1)
				(type default)
			)
			(layer "F.Fab")
		)
		(fp_line
			(start -0.67945 0.3048)
			(end -0.67945 -0.305054)
			(stroke
				(width 0.1)
				(type default)
			)
			(layer "F.Fab")
		)
		(fp_line
			(start -0.12065 -0.305054)
			(end -0.12065 -0.2794)
			(stroke
				(width 0.1)
				(type default)
			)
			(layer "F.Fab")
		)
		(fp_line
			(start -0.12065 -0.2794)
			(end 0.12065 -0.2794)
			(stroke
				(width 0.1)
				(type default)
			)
			(layer "F.Fab")
		)
		(fp_line
			(start -0.12065 0.2794)
			(end -0.12065 0.3048)
			(stroke
				(width 0.1)
				(type default)
			)
			(layer "F.Fab")
		)
		(fp_line
			(start -0.12065 0.3048)
			(end -0.67945 0.3048)
			(stroke
				(width 0.1)
				(type default)
			)
			(layer "F.Fab")
		)
		(fp_line
			(start 0.120396 0.2794)
			(end -0.12065 0.2794)
			(stroke
				(width 0.1)
				(type default)
			)
			(layer "F.Fab")
		)
		(fp_line
			(start 0.120396 0.3048)
			(end 0.120396 0.2794)
			(stroke
				(width 0.1)
				(type default)
			)
			(layer "F.Fab")
		)
		(fp_line
			(start 0.12065 -0.3048)
			(end 0.67945 -0.3048)
			(stroke
				(width 0.1)
				(type default)
			)
			(layer "F.Fab")
		)
		(fp_line
			(start 0.12065 -0.2794)
			(end 0.12065 -0.3048)
			(stroke
				(width 0.1)
				(type default)
			)
			(layer "F.Fab")
		)
		(fp_line
			(start 0.67945 -0.3048)
			(end 0.67945 0.3048)
			(stroke
				(width 0.1)
				(type default)
			)
			(layer "F.Fab")
		)
		(fp_line
			(start 0.67945 0.3048)
			(end 0.120396 0.3048)
			(stroke
				(width 0.1)
				(type default)
			)
			(layer "F.Fab")
		)
		(pad "1" smd circle
			(at -0.40005 0)
			(size 0 0)
			(layers "F.Cu" "F.Mask" "F.Paste")
			(net "P5V")
		)
		(pad "2" smd circle
			(at 0.40005 0)
			(size 0 0)
			(layers "F.Cu" "F.Mask" "F.Paste")
			(net "PVCCFA_EHV_FIVRA_CPU1_PVCC2")
		)
	)
)
